(kicad_pcb
	(version 20260206)
	(generator "pcbnew")
	(generator_version "10.0")
	(general
		(thickness 1.6)
		(legacy_teardrops no)
	)
	(paper "A4")
	(title_block
		(title "04192023_DAF0TMB3IC0_F0TG_MB_C_brd_V02_OCP.brd")
		(comment 1 "Grand Teton / footprints 4735-4741 of 8354")
	)
	(layers
		(0 "F.Cu" signal "TOP")
		(4 "In1.Cu" signal "GND")
		(6 "In2.Cu" signal "IN1")
		(8 "In3.Cu" signal "GND1")
		(10 "In4.Cu" signal "IN2")
		(12 "In5.Cu" signal "GND2")
		(14 "In6.Cu" signal "IN3")
		(16 "In7.Cu" signal "GND3")
		(18 "In8.Cu" signal "VCC")
		(20 "In9.Cu" signal "VCC1")
		(22 "In10.Cu" signal "GND4")
		(24 "In11.Cu" signal "IN4")
		(26 "In12.Cu" signal "GND5")
		(28 "In13.Cu" signal "IN5")
		(30 "In14.Cu" signal "GND6")
		(32 "In15.Cu" signal "IN6")
		(34 "In16.Cu" signal "GND7")
		(2 "B.Cu" signal "BOTTOM")
		(9 "F.Adhes" user "F.Adhesive")
		(11 "B.Adhes" user "B.Adhesive")
		(13 "F.Paste" user "Package Geometry/Pastemask Top")
		(15 "B.Paste" user "Package Geometry/Pastemask Bottom")
		(5 "F.SilkS" user "Ref Des/Silkscreen Top")
		(7 "B.SilkS" user "Ref Des/Silkscreen Bottom")
		(1 "F.Mask" user "Board Geometry/Soldermask Top")
		(3 "B.Mask" user "Board Geometry/Soldermask Bottom")
		(17 "Dwgs.User" user "User.Drawings")
		(19 "Cmts.User" user "User.Comments")
		(21 "Eco1.User" user "User.Eco1")
		(23 "Eco2.User" user "User.Eco2")
		(25 "Edge.Cuts" user "Board Geometry/Outline")
		(27 "Margin" user)
		(31 "F.CrtYd" user "Package Geometry/Place Bound Top")
		(29 "B.CrtYd" user "Package Geometry/Place Bound Bottom")
		(35 "F.Fab" user "Ref Des/Assembly Top")
		(33 "B.Fab" user "Ref Des/Assembly Bottom")
	)
	(footprint ""
		(layer "F.Cu")
		(at 163.734496 -117.310662 180)
		(property "Reference" "R6142"
			(at 0 0 180)
			(layer "F.SilkS")
			(hide yes)
			(effects
				(font
					(size 1.27 1.27)
				)
			)
		)
		(property "Value" ""
			(at 0 0 180)
			(layer "F.Fab")
			(effects
				(font
					(size 1.27 1.27)
				)
			)
		)
		(duplicate_pad_numbers_are_jumpers no)
		(fp_line
			(start 0.7874 0.4064)
			(end -0.7874 0.4064)
			(stroke
				(width 0.1524)
				(type default)
			)
			(layer "F.SilkS")
		)
		(fp_line
			(start 0.7874 -0.4064)
			(end 0.7874 0.4064)
			(stroke
				(width 0.1524)
				(type default)
			)
			(layer "F.SilkS")
		)
		(fp_line
			(start -0.7874 0.4064)
			(end -0.7874 -0.4064)
			(stroke
				(width 0.1524)
				(type default)
			)
			(layer "F.SilkS")
		)
		(fp_line
			(start -0.7874 -0.4064)
			(end 0.7874 -0.4064)
			(stroke
				(width 0.1524)
				(type default)
			)
			(layer "F.SilkS")
		)
		(fp_line
			(start 0.67945 0.3048)
			(end 0.120396 0.3048)
			(stroke
				(width 0.1)
				(type default)
			)
			(layer "F.Fab")
		)
		(fp_line
			(start 0.67945 -0.3048)
			(end 0.67945 0.3048)
			(stroke
				(width 0.1)
				(type default)
			)
			(layer "F.Fab")
		)
		(fp_line
			(start 0.12065 -0.2794)
			(end 0.12065 -0.3048)
			(stroke
				(width 0.1)
				(type default)
			)
			(layer "F.Fab")
		)
		(fp_line
			(start 0.12065 -0.3048)
			(end 0.67945 -0.3048)
			(stroke
				(width 0.1)
				(type default)
			)
			(layer "F.Fab")
		)
		(fp_line
			(start 0.120396 0.3048)
			(end 0.120396 0.2794)
			(stroke
				(width 0.1)
				(type default)
			)
			(layer "F.Fab")
		)
		(fp_line
			(start 0.120396 0.2794)
			(end -0.12065 0.2794)
			(stroke
				(width 0.1)
				(type default)
			)
			(layer "F.Fab")
		)
		(fp_line
			(start -0.12065 0.3048)
			(end -0.67945 0.3048)
			(stroke
				(width 0.1)
				(type default)
			)
			(layer "F.Fab")
		)
		(fp_line
			(start -0.12065 0.2794)
			(end -0.12065 0.3048)
			(stroke
				(width 0.1)
				(type default)
			)
			(layer "F.Fab")
		)
		(fp_line
			(start -0.12065 -0.2794)
			(end 0.12065 -0.2794)
			(stroke
				(width 0.1)
				(type default)
			)
			(layer "F.Fab")
		)
		(fp_line
			(start -0.12065 -0.305054)
			(end -0.12065 -0.2794)
			(stroke
				(width 0.1)
				(type default)
			)
			(layer "F.Fab")
		)
		(fp_line
			(start -0.67945 0.3048)
			(end -0.67945 -0.305054)
			(stroke
				(width 0.1)
				(type default)
			)
			(layer "F.Fab")
		)
		(fp_line
			(start -0.67945 -0.305054)
			(end -0.12065 -0.305054)
			(stroke
				(width 0.1)
				(type default)
			)
			(layer "F.Fab")
		)
		(pad "1" smd circle
			(at -0.40005 0 180)
			(size 0 0)
			(layers "F.Cu" "F.Mask" "F.Paste")
			(net "FM_BOARD_BMC_SKU_ID3")
		)
		(pad "2" smd circle
			(at 0.40005 0 180)
			(size 0 0)
			(layers "F.Cu" "F.Mask" "F.Paste")
			(net "GND")
		)
	)
	(footprint ""
		(layer "F.Cu")
		(at 441.863226 -19.059906)
		(property "Reference" "R1324"
			(at 0.350774 2.703576 0)
			(unlocked yes)
			(layer "F.SilkS")
			(effects
				(font
					(size 0.7874 0.5842)
					(thickness 0.1524)
				)
				(justify left)
			)
		)
		(property "Value" ""
			(at 0 0 0)
			(layer "F.Fab")
			(effects
				(font
					(size 1.27 1.27)
				)
			)
		)
		(duplicate_pad_numbers_are_jumpers no)
		(fp_line
			(start -3.937508 -1.8796)
			(end -3.937508 1.8796)
			(stroke
				(width 0.1524)
				(type default)
			)
			(layer "F.SilkS")
		)
		(fp_line
			(start -3.937508 1.8796)
			(end 3.937508 1.8796)
			(stroke
				(width 0.1524)
				(type default)
			)
			(layer "F.SilkS")
		)
		(fp_line
			(start 3.937508 -1.8796)
			(end -3.937508 -1.8796)
			(stroke
				(width 0.1524)
				(type default)
			)
			(layer "F.SilkS")
		)
		(fp_line
			(start 3.937508 1.8796)
			(end 3.937508 -1.8796)
			(stroke
				(width 0.1524)
				(type default)
			)
			(layer "F.SilkS")
		)
		(fp_line
			(start -3.275076 -1.674876)
			(end -3.275076 1.674876)
			(stroke
				(width 0.1)
				(type default)
			)
			(layer "F.Fab")
		)
		(fp_line
			(start -3.275076 1.674876)
			(end 3.275076 1.674876)
			(stroke
				(width 0.1)
				(type default)
			)
			(layer "F.Fab")
		)
		(fp_line
			(start 3.275076 -1.674876)
			(end -3.275076 -1.674876)
			(stroke
				(width 0.1)
				(type default)
			)
			(layer "F.Fab")
		)
		(fp_line
			(start 3.275076 1.674876)
			(end 3.275076 -1.674876)
			(stroke
				(width 0.1)
				(type default)
			)
			(layer "F.Fab")
		)
		(pad "1" smd rect
			(at -2.350008 0)
			(size 2.921 3.5052)
			(layers "F.Cu" "F.Mask" "F.Paste")
			(net "P12V_OCP_SFF_R")
		)
		(pad "2" smd rect
			(at 2.350008 0)
			(size 2.921 3.5052)
			(layers "F.Cu" "F.Mask" "F.Paste")
			(net "P12V_OCP_SFF")
		)
	)
	(footprint ""
		(layer "F.Cu")
		(at 371.921278 -136.608058 180)
		(property "Reference" "C5017"
			(at 0 0 180)
			(layer "F.SilkS")
			(hide yes)
			(effects
				(font
					(size 1.27 1.27)
				)
			)
		)
		(property "Value" ""
			(at 0 0 180)
			(layer "F.Fab")
			(effects
				(font
					(size 1.27 1.27)
				)
			)
		)
		(duplicate_pad_numbers_are_jumpers no)
		(fp_line
			(start 0.7874 0.4064)
			(end -0.7874 0.4064)
			(stroke
				(width 0.1524)
				(type default)
			)
			(layer "F.SilkS")
		)
		(fp_line
			(start 0.7874 -0.4064)
			(end 0.7874 0.4064)
			(stroke
				(width 0.1524)
				(type default)
			)
			(layer "F.SilkS")
		)
		(fp_line
			(start -0.7874 0.4064)
			(end -0.7874 -0.4064)
			(stroke
				(width 0.1524)
				(type default)
			)
			(layer "F.SilkS")
		)
		(fp_line
			(start -0.7874 -0.4064)
			(end 0.7874 -0.4064)
			(stroke
				(width 0.1524)
				(type default)
			)
			(layer "F.SilkS")
		)
		(fp_line
			(start 0.67945 0.3048)
			(end 0.120396 0.3048)
			(stroke
				(width 0.1)
				(type default)
			)
			(layer "F.Fab")
		)
		(fp_line
			(start 0.67945 -0.3048)
			(end 0.67945 0.3048)
			(stroke
				(width 0.1)
				(type default)
			)
			(layer "F.Fab")
		)
		(fp_line
			(start 0.12065 -0.2794)
			(end 0.12065 -0.3048)
			(stroke
				(width 0.1)
				(type default)
			)
			(layer "F.Fab")
		)
		(fp_line
			(start 0.12065 -0.3048)
			(end 0.67945 -0.3048)
			(stroke
				(width 0.1)
				(type default)
			)
			(layer "F.Fab")
		)
		(fp_line
			(start 0.120396 0.3048)
			(end 0.120396 0.2794)
			(stroke
				(width 0.1)
				(type default)
			)
			(layer "F.Fab")
		)
		(fp_line
			(start 0.120396 0.2794)
			(end -0.12065 0.2794)
			(stroke
				(width 0.1)
				(type default)
			)
			(layer "F.Fab")
		)
		(fp_line
			(start -0.12065 0.3048)
			(end -0.67945 0.3048)
			(stroke
				(width 0.1)
				(type default)
			)
			(layer "F.Fab")
		)
		(fp_line
			(start -0.12065 0.2794)
			(end -0.12065 0.3048)
			(stroke
				(width 0.1)
				(type default)
			)
			(layer "F.Fab")
		)
		(fp_line
			(start -0.12065 -0.2794)
			(end 0.12065 -0.2794)
			(stroke
				(width 0.1)
				(type default)
			)
			(layer "F.Fab")
		)
		(fp_line
			(start -0.12065 -0.305054)
			(end -0.12065 -0.2794)
			(stroke
				(width 0.1)
				(type default)
			)
			(layer "F.Fab")
		)
		(fp_line
			(start -0.67945 0.3048)
			(end -0.67945 -0.305054)
			(stroke
				(width 0.1)
				(type default)
			)
			(layer "F.Fab")
		)
		(fp_line
			(start -0.67945 -0.305054)
			(end -0.12065 -0.305054)
			(stroke
				(width 0.1)
				(type default)
			)
			(layer "F.Fab")
		)
		(pad "1" smd circle
			(at -0.40005 0 180)
			(size 0 0)
			(layers "F.Cu" "F.Mask" "F.Paste")
			(net "GND")
		)
		(pad "2" smd circle
			(at 0.40005 0 180)
			(size 0 0)
			(layers "F.Cu" "F.Mask" "F.Paste")
			(net "PWRGD_PVDDCR_CPU0_P0")
		)
	)
	(footprint ""
		(layer "F.Cu")
		(at 70.21576 -344.814906)
		(property "Reference" "H13"
			(at -2.6416 -4.08813 0)
			(unlocked yes)
			(layer "F.SilkS")
			(effects
				(font
					(size 0.7874 0.5842)
					(thickness 0.1524)
				)
				(justify left)
			)
		)
		(property "Value" ""
			(at 0 0 0)
			(layer "F.Fab")
			(effects
				(font
					(size 1.27 1.27)
				)
			)
		)
		(duplicate_pad_numbers_are_jumpers no)
		(pad "1" thru_hole circle
			(at 0 0)
			(size 6.1976 6.1976)
			(drill 3.7338)
			(layers "*.Cu" "*.Mask")
			(remove_unused_layers no)
			(net "GND")
			(clearance -0.9779)
			(padstack
				(mode front_inner_back)
				(layer "Inner"
					(shape circle)
					(size 5.5372 5.5372)
					(clearance -0.6477)
				)
				(layer "B.Cu"
					(shape circle)
					(size 6.1976 6.1976)
					(clearance -0.9779)
				)
			)
		)
	)
	(footprint ""
		(layer "F.Cu")
		(at 66.952114 -163.71697)
		(property "Reference" "PR423"
			(at 0 0 0)
			(layer "F.SilkS")
			(hide yes)
			(effects
				(font
					(size 1.27 1.27)
				)
			)
		)
		(property "Value" ""
			(at 0 0 0)
			(layer "F.Fab")
			(effects
				(font
					(size 1.27 1.27)
				)
			)
		)
		(duplicate_pad_numbers_are_jumpers no)
		(fp_line
			(start -0.7874 -0.4064)
			(end 0.7874 -0.4064)
			(stroke
				(width 0.1524)
				(type default)
			)
			(layer "F.SilkS")
		)
		(fp_line
			(start -0.7874 0.4064)
			(end -0.7874 -0.4064)
			(stroke
				(width 0.1524)
				(type default)
			)
			(layer "F.SilkS")
		)
		(fp_line
			(start 0.7874 -0.4064)
			(end 0.7874 0.4064)
			(stroke
				(width 0.1524)
				(type default)
			)
			(layer "F.SilkS")
		)
		(fp_line
			(start 0.7874 0.4064)
			(end -0.7874 0.4064)
			(stroke
				(width 0.1524)
				(type default)
			)
			(layer "F.SilkS")
		)
		(fp_line
			(start -0.67945 -0.305054)
			(end -0.12065 -0.305054)
			(stroke
				(width 0.1)
				(type default)
			)
			(layer "F.Fab")
		)
		(fp_line
			(start -0.67945 0.3048)
			(end -0.67945 -0.305054)
			(stroke
				(width 0.1)
				(type default)
			)
			(layer "F.Fab")
		)
		(fp_line
			(start -0.12065 -0.305054)
			(end -0.12065 -0.2794)
			(stroke
				(width 0.1)
				(type default)
			)
			(layer "F.Fab")
		)
		(fp_line
			(start -0.12065 -0.2794)
			(end 0.12065 -0.2794)
			(stroke
				(width 0.1)
				(type default)
			)
			(layer "F.Fab")
		)
		(fp_line
			(start -0.12065 0.2794)
			(end -0.12065 0.3048)
			(stroke
				(width 0.1)
				(type default)
			)
			(layer "F.Fab")
		)
		(fp_line
			(start -0.12065 0.3048)
			(end -0.67945 0.3048)
			(stroke
				(width 0.1)
				(type default)
			)
			(layer "F.Fab")
		)
		(fp_line
			(start 0.120396 0.2794)
			(end -0.12065 0.2794)
			(stroke
				(width 0.1)
				(type default)
			)
			(layer "F.Fab")
		)
		(fp_line
			(start 0.120396 0.3048)
			(end 0.120396 0.2794)
			(stroke
				(width 0.1)
				(type default)
			)
			(layer "F.Fab")
		)
		(fp_line
			(start 0.12065 -0.3048)
			(end 0.67945 -0.3048)
			(stroke
				(width 0.1)
				(type default)
			)
			(layer "F.Fab")
		)
		(fp_line
			(start 0.12065 -0.2794)
			(end 0.12065 -0.3048)
			(stroke
				(width 0.1)
				(type default)
			)
			(layer "F.Fab")
		)
		(fp_line
			(start 0.67945 -0.3048)
			(end 0.67945 0.3048)
			(stroke
				(width 0.1)
				(type default)
			)
			(layer "F.Fab")
		)
		(fp_line
			(start 0.67945 0.3048)
			(end 0.120396 0.3048)
			(stroke
				(width 0.1)
				(type default)
			)
			(layer "F.Fab")
		)
		(pad "1" smd circle
			(at -0.40005 0)
			(size 0 0)
			(layers "F.Cu" "F.Mask" "F.Paste")
			(net "GND")
		)
		(pad "2" smd circle
			(at 0.40005 0)
			(size 0 0)
			(layers "F.Cu" "F.Mask" "F.Paste")
			(net "PVDDCR_CPU0_P1_LSET6")
		)
	)
	(footprint ""
		(layer "F.Cu")
		(at 309.455312 -351.368106 90)
		(property "Reference" "PR89"
			(at 0 0 90)
			(layer "F.SilkS")
			(hide yes)
			(effects
				(font
					(size 1.27 1.27)
				)
			)
		)
		(property "Value" ""
			(at 0 0 90)
			(layer "F.Fab")
			(effects
				(font
					(size 1.27 1.27)
				)
			)
		)
		(duplicate_pad_numbers_are_jumpers no)
		(fp_line
			(start 0.7874 -0.4064)
			(end 0.7874 0.4064)
			(stroke
				(width 0.1524)
				(type default)
			)
			(layer "F.SilkS")
		)
		(fp_line
			(start -0.7874 -0.4064)
			(end 0.7874 -0.4064)
			(stroke
				(width 0.1524)
				(type default)
			)
			(layer "F.SilkS")
		)
		(fp_line
			(start 0.7874 0.4064)
			(end -0.7874 0.4064)
			(stroke
				(width 0.1524)
				(type default)
			)
			(layer "F.SilkS")
		)
		(fp_line
			(start -0.7874 0.4064)
			(end -0.7874 -0.4064)
			(stroke
				(width 0.1524)
				(type default)
			)
			(layer "F.SilkS")
		)
		(fp_line
			(start -0.12065 -0.305054)
			(end -0.12065 -0.2794)
			(stroke
				(width 0.1)
				(type default)
			)
			(layer "F.Fab")
		)
		(fp_line
			(start -0.67945 -0.305054)
			(end -0.12065 -0.305054)
			(stroke
				(width 0.1)
				(type default)
			)
			(layer "F.Fab")
		)
		(fp_line
			(start 0.67945 -0.3048)
			(end 0.67945 0.3048)
			(stroke
				(width 0.1)
				(type default)
			)
			(layer "F.Fab")
		)
		(fp_line
			(start 0.12065 -0.3048)
			(end 0.67945 -0.3048)
			(stroke
				(width 0.1)
				(type default)
			)
			(layer "F.Fab")
		)
		(fp_line
			(start 0.12065 -0.2794)
			(end 0.12065 -0.3048)
			(stroke
				(width 0.1)
				(type default)
			)
			(layer "F.Fab")
		)
		(fp_line
			(start -0.12065 -0.2794)
			(end 0.12065 -0.2794)
			(stroke
				(width 0.1)
				(type default)
			)
			(layer "F.Fab")
		)
		(fp_line
			(start 0.120396 0.2794)
			(end -0.12065 0.2794)
			(stroke
				(width 0.1)
				(type default)
			)
			(layer "F.Fab")
		)
		(fp_line
			(start -0.12065 0.2794)
			(end -0.12065 0.3048)
			(stroke
				(width 0.1)
				(type default)
			)
			(layer "F.Fab")
		)
		(fp_line
			(start 0.67945 0.3048)
			(end 0.120396 0.3048)
			(stroke
				(width 0.1)
				(type default)
			)
			(layer "F.Fab")
		)
		(fp_line
			(start 0.120396 0.3048)
			(end 0.120396 0.2794)
			(stroke
				(width 0.1)
				(type default)
			)
			(layer "F.Fab")
		)
		(fp_line
			(start -0.12065 0.3048)
			(end -0.67945 0.3048)
			(stroke
				(width 0.1)
				(type default)
			)
			(layer "F.Fab")
		)
		(fp_line
			(start -0.67945 0.3048)
			(end -0.67945 -0.305054)
			(stroke
				(width 0.1)
				(type default)
			)
			(layer "F.Fab")
		)
		(pad "1" smd circle
			(at -0.40005 0 90)
			(size 0 0)
			(layers "F.Cu" "F.Mask" "F.Paste")
			(net "SW_PVDDCR_CPU1_P0_BOOT4")
		)
		(pad "2" smd circle
			(at 0.40005 0 90)
			(size 0 0)
			(layers "F.Cu" "F.Mask" "F.Paste")
			(net "SW_PVDDCR_CPU1_P0_BOOT4_R")
		)
	)
	(footprint ""
		(layer "F.Cu")
		(at 178.764946 -413.815022 -90)
		(property "Reference" "R2694"
			(at 0 0 270)
			(layer "F.SilkS")
			(hide yes)
			(effects
				(font
					(size 1.27 1.27)
				)
			)
		)
		(property "Value" ""
			(at 0 0 270)
			(layer "F.Fab")
			(effects
				(font
					(size 1.27 1.27)
				)
			)
		)
		(duplicate_pad_numbers_are_jumpers no)
		(fp_line
			(start -0.7874 0.4064)
			(end -0.7874 -0.4064)
			(stroke
				(width 0.1524)
				(type default)
			)
			(layer "F.SilkS")
		)
		(fp_line
			(start 0.7874 0.4064)
			(end -0.7874 0.4064)
			(stroke
				(width 0.1524)
				(type default)
			)
			(layer "F.SilkS")
		)
		(fp_line
			(start -0.7874 -0.4064)
			(end 0.7874 -0.4064)
			(stroke
				(width 0.1524)
				(type default)
			)
			(layer "F.SilkS")
		)
		(fp_line
			(start 0.7874 -0.4064)
			(end 0.7874 0.4064)
			(stroke
				(width 0.1524)
				(type default)
			)
			(layer "F.SilkS")
		)
		(fp_line
			(start -0.67945 0.3048)
			(end -0.67945 -0.305054)
			(stroke
				(width 0.1)
				(type default)
			)
			(layer "F.Fab")
		)
		(fp_line
			(start -0.12065 0.3048)
			(end -0.67945 0.3048)
			(stroke
				(width 0.1)
				(type default)
			)
			(layer "F.Fab")
		)
		(fp_line
			(start 0.120396 0.3048)
			(end 0.120396 0.2794)
			(stroke
				(width 0.1)
				(type default)
			)
			(layer "F.Fab")
		)
		(fp_line
			(start 0.67945 0.3048)
			(end 0.120396 0.3048)
			(stroke
				(width 0.1)
				(type default)
			)
			(layer "F.Fab")
		)
		(fp_line
			(start -0.12065 0.2794)
			(end -0.12065 0.3048)
			(stroke
				(width 0.1)
				(type default)
			)
			(layer "F.Fab")
		)
		(fp_line
			(start 0.120396 0.2794)
			(end -0.12065 0.2794)
			(stroke
				(width 0.1)
				(type default)
			)
			(layer "F.Fab")
		)
		(fp_line
			(start -0.12065 -0.2794)
			(end 0.12065 -0.2794)
			(stroke
				(width 0.1)
				(type default)
			)
			(layer "F.Fab")
		)
		(fp_line
			(start 0.12065 -0.2794)
			(end 0.12065 -0.3048)
			(stroke
				(width 0.1)
				(type default)
			)
			(layer "F.Fab")
		)
		(fp_line
			(start 0.12065 -0.3048)
			(end 0.67945 -0.3048)
			(stroke
				(width 0.1)
				(type default)
			)
			(layer "F.Fab")
		)
		(fp_line
			(start 0.67945 -0.3048)
			(end 0.67945 0.3048)
			(stroke
				(width 0.1)
				(type default)
			)
			(layer "F.Fab")
		)
		(fp_line
			(start -0.67945 -0.305054)
			(end -0.12065 -0.305054)
			(stroke
				(width 0.1)
				(type default)
			)
			(layer "F.Fab")
		)
		(fp_line
			(start -0.12065 -0.305054)
			(end -0.12065 -0.2794)
			(stroke
				(width 0.1)
				(type default)
			)
			(layer "F.Fab")
		)
		(pad "1" smd circle
			(at -0.40005 0 270)
			(size 0 0)
			(layers "F.Cu" "F.Mask" "F.Paste")
			(net "TCA9539_0_ADD1")
		)
		(pad "2" smd circle
			(at 0.40005 0 270)
			(size 0 0)
			(layers "F.Cu" "F.Mask" "F.Paste")
			(net "GND")
		)
	)
)
